# T6G (Grand Teton) — schematic netlist excerpt (pin names and nets, part order shuffled) for the footprints in the layout excerpt that follows; sources: Cadence DE-HDL packaged netlist, KiCad conversion of 04192023_DAF0TMB3IC0_F0TG_MB_C_brd_V02_OCP.brd

C3931  Q_CAP  22UF 4V 20% X6S  pkg C0402  page 70 : A = PVDDCR_SOC_P0 ; B = GND
R1399  Q_RES  4.7K 5% CHIP  pkg 0201LF  page 185 : A = P1V8_CPU1_RT_1D ; B = SMB_RT_CPU1_P3_ROM_MUX_2D_R_SDA
R848  Q_RES  0 5% CHIP  pkg 0201LF  page 185 : A = RST_SMB_RT_ROM_R1_N ; B = RST_SMB_RT_ROM_N

(kicad_pcb
	(version 20260206)
	(generator "pcbnew")
	(generator_version "10.0")
	(general
		(thickness 1.6)
		(legacy_teardrops no)
	)
	(paper "A4")
	(title_block
		(title "04192023_DAF0TMB3IC0_F0TG_MB_C_brd_V02_OCP.brd")
		(comment 1 "Grand Teton / footprints 6396-6398 of 8354")
	)
	(layers
		(0 "F.Cu" signal "TOP")
		(4 "In1.Cu" signal "GND")
		(6 "In2.Cu" signal "IN1")
		(8 "In3.Cu" signal "GND1")
		(10 "In4.Cu" signal "IN2")
		(12 "In5.Cu" signal "GND2")
		(14 "In6.Cu" signal "IN3")
		(16 "In7.Cu" signal "GND3")
		(18 "In8.Cu" signal "VCC")
		(20 "In9.Cu" signal "VCC1")
		(22 "In10.Cu" signal "GND4")
		(24 "In11.Cu" signal "IN4")
		(26 "In12.Cu" signal "GND5")
		(28 "In13.Cu" signal "IN5")
		(30 "In14.Cu" signal "GND6")
		(32 "In15.Cu" signal "IN6")
		(34 "In16.Cu" signal "GND7")
		(2 "B.Cu" signal "BOTTOM")
		(9 "F.Adhes" user "F.Adhesive")
		(11 "B.Adhes" user "B.Adhesive")
		(13 "F.Paste" user "Package Geometry/Pastemask Top")
		(15 "B.Paste" user "Package Geometry/Pastemask Bottom")
		(5 "F.SilkS" user "Ref Des/Silkscreen Top")
		(7 "B.SilkS" user "Ref Des/Silkscreen Bottom")
		(1 "F.Mask" user "Board Geometry/Soldermask Top")
		(3 "B.Mask" user "Board Geometry/Soldermask Bottom")
		(17 "Dwgs.User" user "User.Drawings")
		(19 "Cmts.User" user "User.Comments")
		(21 "Eco1.User" user "User.Eco1")
		(23 "Eco2.User" user "User.Eco2")
		(25 "Edge.Cuts" user "Board Geometry/Outline")
		(27 "Margin" user)
		(31 "F.CrtYd" user "Package Geometry/Place Bound Top")
		(29 "B.CrtYd" user "Package Geometry/Place Bound Bottom")
		(35 "F.Fab" user "Ref Des/Assembly Top")
		(33 "B.Fab" user "Ref Des/Assembly Bottom")
	)
	(footprint ""
		(layer "B.Cu")
		(at 359.721404 -252.41631 180)
		(property "Reference" "C3931"
			(at 0 0 0)
			(layer "B.SilkS")
			(hide yes)
			(effects
				(font
					(size 1.27 1.27)
				)
				(justify mirror)
			)
		)
		(property "Value" ""
			(at 0 0 0)
			(layer "B.Fab")
			(effects
				(font
					(size 1.27 1.27)
				)
				(justify mirror)
			)
		)
		(duplicate_pad_numbers_are_jumpers no)
		(fp_line
			(start 0.7874 0.4064)
			(end 0.7874 -0.4064)
			(stroke
				(width 0.1524)
				(type default)
			)
			(layer "B.SilkS")
		)
		(fp_line
			(start 0.7874 -0.4064)
			(end -0.7874 -0.4064)
			(stroke
				(width 0.1524)
				(type default)
			)
			(layer "B.SilkS")
		)
		(fp_line
			(start -0.7874 0.4064)
			(end 0.7874 0.4064)
			(stroke
				(width 0.1524)
				(type default)
			)
			(layer "B.SilkS")
		)
		(fp_line
			(start -0.7874 -0.4064)
			(end -0.7874 0.4064)
			(stroke
				(width 0.1524)
				(type default)
			)
			(layer "B.SilkS")
		)
		(fp_line
			(start 0.67945 0.3048)
			(end 0.67945 -0.305054)
			(stroke
				(width 0.1)
				(type default)
			)
			(layer "B.Fab")
		)
		(fp_line
			(start 0.67945 -0.305054)
			(end 0.12065 -0.305054)
			(stroke
				(width 0.1)
				(type default)
			)
			(layer "B.Fab")
		)
		(fp_line
			(start 0.12065 0.3048)
			(end 0.67945 0.3048)
			(stroke
				(width 0.1)
				(type default)
			)
			(layer "B.Fab")
		)
		(fp_line
			(start 0.12065 0.2794)
			(end 0.12065 0.3048)
			(stroke
				(width 0.1)
				(type default)
			)
			(layer "B.Fab")
		)
		(fp_line
			(start 0.12065 -0.2794)
			(end -0.12065 -0.2794)
			(stroke
				(width 0.1)
				(type default)
			)
			(layer "B.Fab")
		)
		(fp_line
			(start 0.12065 -0.305054)
			(end 0.12065 -0.2794)
			(stroke
				(width 0.1)
				(type default)
			)
			(layer "B.Fab")
		)
		(fp_line
			(start -0.120396 0.3048)
			(end -0.120396 0.2794)
			(stroke
				(width 0.1)
				(type default)
			)
			(layer "B.Fab")
		)
		(fp_line
			(start -0.120396 0.2794)
			(end 0.12065 0.2794)
			(stroke
				(width 0.1)
				(type default)
			)
			(layer "B.Fab")
		)
		(fp_line
			(start -0.12065 -0.2794)
			(end -0.12065 -0.3048)
			(stroke
				(width 0.1)
				(type default)
			)
			(layer "B.Fab")
		)
		(fp_line
			(start -0.12065 -0.3048)
			(end -0.67945 -0.3048)
			(stroke
				(width 0.1)
				(type default)
			)
			(layer "B.Fab")
		)
		(fp_line
			(start -0.67945 0.3048)
			(end -0.120396 0.3048)
			(stroke
				(width 0.1)
				(type default)
			)
			(layer "B.Fab")
		)
		(fp_line
			(start -0.67945 -0.3048)
			(end -0.67945 0.3048)
			(stroke
				(width 0.1)
				(type default)
			)
			(layer "B.Fab")
		)
		(pad "1" smd circle
			(at 0.40005 0)
			(size 0 0)
			(layers "B.Cu" "B.Mask" "B.Paste")
			(net "PVDDCR_SOC_P0")
		)
		(pad "2" smd circle
			(at -0.40005 0)
			(size 0 0)
			(layers "B.Cu" "B.Mask" "B.Paste")
			(net "GND")
		)
	)
	(footprint ""
		(layer "B.Cu")
		(at 239.903 -338.455)
		(property "Reference" "R1399"
			(at 0 0 0)
			(layer "B.SilkS")
			(hide yes)
			(effects
				(font
					(size 1.27 1.27)
				)
				(justify mirror)
			)
		)
		(property "Value" ""
			(at 0 0 0)
			(layer "B.Fab")
			(effects
				(font
					(size 1.27 1.27)
				)
				(justify mirror)
			)
		)
		(duplicate_pad_numbers_are_jumpers no)
		(fp_line
			(start -0.32512 -0.175006)
			(end -0.32512 0.175006)
			(stroke
				(width 0.1)
				(type default)
			)
			(layer "B.Fab")
		)
		(fp_line
			(start -0.32512 0.175006)
			(end 0.32512 0.175006)
			(stroke
				(width 0.1)
				(type default)
			)
			(layer "B.Fab")
		)
		(fp_line
			(start 0.32512 -0.175006)
			(end -0.32512 -0.175006)
			(stroke
				(width 0.1)
				(type default)
			)
			(layer "B.Fab")
		)
		(fp_line
			(start 0.32512 0.175006)
			(end 0.32512 -0.175006)
			(stroke
				(width 0.1)
				(type default)
			)
			(layer "B.Fab")
		)
		(pad "1" smd rect
			(at 0.2667 0 180)
			(size 0.3048 0.381)
			(layers "B.Cu" "B.Mask" "B.Paste")
			(net "P1V8_CPU1_RT_1D")
		)
		(pad "2" smd rect
			(at -0.2667 0)
			(size 0.3048 0.381)
			(layers "B.Cu" "B.Mask" "B.Paste")
			(net "SMB_RT_CPU1_P3_ROM_MUX_2D_R_SDA")
		)
	)
	(footprint ""
		(layer "B.Cu")
		(at 241.140488 -332.613 180)
		(property "Reference" "R848"
			(at 0 0 0)
			(layer "B.SilkS")
			(hide yes)
			(effects
				(font
					(size 1.27 1.27)
				)
				(justify mirror)
			)
		)
		(property "Value" ""
			(at 0 0 0)
			(layer "B.Fab")
			(effects
				(font
					(size 1.27 1.27)
				)
				(justify mirror)
			)
		)
		(duplicate_pad_numbers_are_jumpers no)
		(fp_line
			(start 0.32512 0.175006)
			(end 0.32512 -0.175006)
			(stroke
				(width 0.1)
				(type default)
			)
			(layer "B.Fab")
		)
		(fp_line
			(start 0.32512 -0.175006)
			(end -0.32512 -0.175006)
			(stroke
				(width 0.1)
				(type default)
			)
			(layer "B.Fab")
		)
		(fp_line
			(start -0.32512 0.175006)
			(end 0.32512 0.175006)
			(stroke
				(width 0.1)
				(type default)
			)
			(layer "B.Fab")
		)
		(fp_line
			(start -0.32512 -0.175006)
			(end -0.32512 0.175006)
			(stroke
				(width 0.1)
				(type default)
			)
			(layer "B.Fab")
		)
		(pad "1" smd rect
			(at 0.2667 0)
			(size 0.3048 0.381)
			(layers "B.Cu" "B.Mask" "B.Paste")
			(net "RST_SMB_RT_ROM_R1_N")
		)
		(pad "2" smd rect
			(at -0.2667 0 180)
			(size 0.3048 0.381)
			(layers "B.Cu" "B.Mask" "B.Paste")
			(net "RST_SMB_RT_ROM_N")
		)
	)
)
